G04 ================== begin FILE IDENTIFICATION RECORD ==================*
G04 Layout Name:  13948-1b.brd*
G04 Film Name:    DIF_REF_L3*
G04 File Format:  Gerber RS274X*
G04 File Origin:  Cadence Allegro 16.5-S045*
G04 Origin Date:  Thu Nov 13 15:49:16 2014*
G04 *
G04 Layer:  BOARD GEOMETRY/OUTLINE*
G04 Layer:  BOARD GEOMETRY/DIF_REF_L3*
G04 Layer:  BOARD GEOMETRY/PANEL_OUTLINE*
G04 *
G04 Offset:    (0.00 0.00)*
G04 Mirror:    No*
G04 Mode:      Positive*
G04 Rotation:  0*
G04 FullContactRelief:  No*
G04 UndefLineWidth:     6.00*
G04 ================== end FILE IDENTIFICATION RECORD ====================*
%FSLAX35Y35*MOIN*%
%IR0*IPPOS*OFA0.00000B0.00000*MIA0B0*SFA1.00000B1.00000*%
%ADD10C,.004*%
%ADD11C,.005*%
%ADD12C,.006*%
G75*
%LPD*%
G75*
G54D10*
G01X299831Y144328D02*
X299857Y144355D01*
G01D02*
G03X300829Y146700I-2345J2346D01*
G01D02*
Y193169D01*
G01X303677Y144328D02*
G02X303327Y144473I0J495D01*
G01D02*
X302200Y145600D01*
G01D02*
G02X302129Y145771I171J171D01*
G01D02*
Y193170D01*
G01X313402Y156000D02*
X314082Y156681D01*
G01X309698Y163800D02*
G02X308900Y165727I1927J1927D01*
G01D02*
Y188160D01*
G01X305852Y163800D02*
X306785Y164734D01*
G01D02*
G03X307600Y166700I-1966J1967D01*
G01D02*
Y188161D01*
G01X300829Y193169D02*
G02X301443Y194654I2100J1D01*
G01D02*
X337337Y230642D01*
G01X302129Y193170D02*
G02X302363Y193735I800J0D01*
G01D02*
X302364D01*
G01D02*
X329284Y220726D01*
G01X308900Y188160D02*
G02X309828Y190400I3168J0D01*
G01D02*
X314178Y194750D01*
G01X307600Y188161D02*
G02X308908Y191320I4469J0D01*
G01D02*
X313522Y195933D01*
G01D02*
X313639Y196050D01*
G01X322729Y158315D02*
Y153124D01*
G01D02*
G03X323029Y152400I1024J0D01*
G01D02*
X323151Y152278D01*
G01D02*
G03X325029Y151500I1878J1878D01*
G01D02*
G03X325122Y151505I-3J932D01*
G01D02*
G03X325688Y151773I-93J927D01*
G01D02*
X326422Y152507D01*
G01X321429Y158316D02*
Y153123D01*
G01D02*
G03X322109Y151481I2324J1D01*
G01D02*
X322108D01*
G01D02*
X322231Y151358D01*
G01D02*
G03X325031Y150199I2798J2798D01*
G01D02*
G03X325254Y150211I-8J2233D01*
G01D02*
X325807Y150269D01*
G01D02*
G02X326000Y150200I24J-237D01*
G01D02*
G02X326422Y149181I-1019J-1019D01*
G01D02*
Y148944D01*
G01X330122Y160375D02*
G02X329232Y159930I-879J645D01*
G01D02*
X328032D01*
G01D02*
G02X327142Y160375I-11J1090D01*
G01D02*
G03X326252Y160820I-879J-645D01*
G01D02*
X325052D01*
G01D02*
G03X323748Y160280I0J-1844D01*
G01D02*
X323398Y159930D01*
G01D02*
G03X322729Y158315I1615J-1615D01*
G01X332729Y162120D02*
X325053D01*
G01D02*
G03X322828Y161199I-2J-3144D01*
G01D02*
X322478Y160849D01*
G01D02*
G03X321429Y158316I2535J-2534D01*
G01X314082Y156681D02*
G03X314629Y158000I-1319J1320D01*
G01D02*
Y184670D01*
G01X317248Y156000D02*
X316411Y156838D01*
G01D02*
G02X315929Y158000I1162J1163D01*
G01D02*
Y164484D01*
G01D02*
G02X316374Y165374I1090J11D01*
G01D02*
G03X316819Y166264I-645J879D01*
G01D02*
Y167464D01*
G01D02*
G03X316374Y168354I-1090J11D01*
G01D02*
G02X315929Y169244I645J879D01*
G01D02*
Y170444D01*
G01D02*
G02X316374Y171334I1090J11D01*
G01D02*
G03X316819Y172224I-645J879D01*
G01X314629Y184670D02*
G02X315243Y186155I2100J1D01*
G01D02*
X336308Y207220D01*
G01X316819Y172224D02*
Y173424D01*
G01D02*
G03X316374Y174314I-1090J11D01*
G01D02*
G02X315929Y175204I645J879D01*
G01D02*
Y176404D01*
G01D02*
G02X316374Y177294I1090J11D01*
G01D02*
G03X316819Y178184I-645J879D01*
G01D02*
Y179384D01*
G01D02*
G03X316374Y180274I-1090J11D01*
G01D02*
G02X315929Y181164I645J879D01*
G01D02*
Y184670D01*
G01D02*
G02X316163Y185235I799J0D01*
G01D02*
X322934Y192006D01*
G01D02*
X322935D01*
G01D02*
G02X323212Y192211I779J-763D01*
G01D02*
G02X323879Y192321I502J-968D01*
G01D02*
G03X324823Y192635I166J1077D01*
G01D02*
X325672Y193484D01*
G01D02*
G03X325986Y194428I-763J778D01*
G01D02*
G02X326301Y195372I1078J165D01*
G01D02*
X327150Y196221D01*
G01D02*
G02X328093Y196535I778J-763D01*
G01D02*
G03X329037Y196850I165J1077D01*
G01D02*
X329886Y197698D01*
G01D02*
G03X330201Y198642I-763J779D01*
G01X314178Y194750D02*
X314179D01*
G01D02*
X339147Y219718D01*
G01X313639Y196050D02*
X313640D01*
G01D02*
X338227Y220637D01*
G01X329284Y220726D02*
X338257Y229723D01*
G01X336929Y171641D02*
Y165020D01*
G01D02*
G02X332729Y160820I-4200J0D01*
G01D02*
X331012D01*
G01D02*
G03X330122Y160375I-11J-1090D01*
G01X335629Y188000D02*
Y165020D01*
G01D02*
G02X332729Y162120I-2900J0D01*
G01X336929Y188000D02*
Y182361D01*
G01D02*
G03X337374Y181471I1090J-11D01*
G01D02*
G02X337819Y180581I-645J-879D01*
G01D02*
Y179381D01*
G01D02*
G02X337374Y178491I-1090J-11D01*
G01D02*
G03X336929Y177601I645J-879D01*
G01D02*
Y176401D01*
G01D02*
G03X337374Y175511I1090J-11D01*
G01D02*
G02X337819Y174621I-645J-879D01*
G01D02*
Y173421D01*
G01D02*
G02X337374Y172531I-1090J-11D01*
G01D02*
G03X336929Y171641I645J-879D01*
G01X346420Y200862D02*
G03X345476Y200547I-165J-1078D01*
G01D02*
X339757Y194828D01*
G01D02*
G03X336929Y188000I6829J-6828D01*
G01X387646Y244559D02*
X338837Y195748D01*
G01D02*
G03X335628Y188000I7749J-7748D01*
G01D02*
X335629D01*
G01X330201Y198642D02*
G02X330515Y199586I1077J166D01*
G01D02*
X331364Y200435D01*
G01D02*
G02X332308Y200750I779J-763D01*
G01D02*
G03X333252Y201064I166J1077D01*
G01D02*
X334100Y201913D01*
G01D02*
G03X334415Y202857I-762J779D01*
G01D02*
G02X334730Y203801I1077J165D01*
G01D02*
X353229Y222300D01*
G01X336308Y207220D02*
X336309D01*
G01D02*
X365158Y236069D01*
G01X339147Y219718D02*
G02X340091Y220032I778J-763D01*
G01D02*
G03X341035Y220347I165J1078D01*
G01D02*
X341883Y221196D01*
G01X338227Y220637D02*
Y220638D01*
G01D02*
X398771Y281182D01*
G01X337337Y230642D02*
X350097Y243402D01*
G01X338257Y229723D02*
X351016Y242482D01*
G01X341883Y221196D02*
G03X342198Y222140I-762J779D01*
G01D02*
G02X342513Y223084I1077J165D01*
G01D02*
X343361Y223932D01*
G01D02*
G02X344305Y224247I779J-763D01*
G01D02*
G03X345249Y224561I166J1077D01*
G01D02*
X346098Y225410D01*
G01D02*
G03X346412Y226354I-763J778D01*
G01X349690Y204761D02*
X348842Y203913D01*
G01D02*
G03X348527Y202969I763J-779D01*
G01D02*
G02X348213Y202025I-1077J-166D01*
G01D02*
X347364Y201176D01*
G01D02*
G02X346420Y200862I-778J763D01*
G01X362936Y217378D02*
G03X361992Y217063I-165J-1078D01*
G01D02*
X361143Y216214D01*
G01D02*
G03X360829Y215270I763J-778D01*
G01D02*
G02X360514Y214326I-1078J-165D01*
G01D02*
X359665Y213478D01*
G01D02*
G02X358721Y213163I-779J762D01*
G01D02*
G03X357778Y212849I-165J-1077D01*
G01D02*
X353056Y208127D01*
G01D02*
G03X352742Y207183I763J-778D01*
G01D02*
G02X352427Y206239I-1078J-165D01*
G01D02*
X351578Y205391D01*
G01D02*
G02X350634Y205076I-779J762D01*
G01D02*
G03X349690Y204761I-165J-1077D01*
G01X353229Y222300D02*
G02X354173Y222614I778J-763D01*
G01D02*
G03X355117Y222929I165J1078D01*
G01D02*
X355965Y223778D01*
G01D02*
G03X356280Y224722I-762J779D01*
G01D02*
G02X356595Y225666I1077J165D01*
G01D02*
X357443Y226514D01*
G01D02*
G02X358387Y226829I779J-763D01*
G01D02*
G03X359331Y227143I166J1077D01*
G01D02*
X360180Y227992D01*
G01D02*
G03X360494Y228936I-763J778D01*
G01D02*
G02X360809Y229880I1078J165D01*
G01D02*
X361657Y230728D01*
G01D02*
G02X362601Y231043I779J-762D01*
G01D02*
G03X363545Y231358I165J1077D01*
G01X346412Y226354D02*
G02X346727Y227298I1078J165D01*
G01D02*
X347575Y228146D01*
G01D02*
G02X348519Y228461I779J-762D01*
G01D02*
G03X349463Y228776I165J1077D01*
G01D02*
X350312Y229624D01*
G01D02*
G03X350627Y230568I-763J779D01*
G01D02*
G02X350941Y231512I1077J166D01*
G01D02*
X357038Y237609D01*
G01X350097Y243402D02*
G03X351700Y247272I-3870J3870D01*
G01D02*
Y249947D01*
G01D02*
G02X354000Y255500I7852J1D01*
G01X351016Y242482D02*
G03X353000Y247272I-4789J4790D01*
G01D02*
Y249947D01*
G01D02*
G02X354919Y254580I6552J0D01*
G01X357038Y237609D02*
G02X357982Y237923I778J-763D01*
G01D02*
G03X358926Y238238I165J1078D01*
G01D02*
X359774Y239087D01*
G01D02*
G03X360089Y240031I-762J779D01*
G01D02*
G02X360404Y240975I1077J165D01*
G01D02*
X361252Y241823D01*
G01D02*
G02X362196Y242138I779J-763D01*
G01D02*
G03X363140Y242452I166J1077D01*
G01X354000Y255500D02*
X395500Y297000D01*
G01X354919Y254580D02*
X396419Y296080D01*
G01X366206Y221277D02*
X365358Y220429D01*
G01D02*
G03X365043Y219485I762J-779D01*
G01D02*
G02X364728Y218541I-1077J-165D01*
G01D02*
X363880Y217692D01*
G01D02*
G02X362936Y217378I-778J763D01*
G01X379528Y233341D02*
X378680Y232492D01*
G01D02*
G02X377736Y232177I-779J763D01*
G01D02*
G03X376792Y231863I-166J-1077D01*
G01D02*
X369572Y224643D01*
G01D02*
G03X369257Y223699I762J-779D01*
G01D02*
G02X368943Y222755I-1077J-166D01*
G01D02*
X368094Y221907D01*
G01D02*
G02X367150Y221592I-779J762D01*
G01D02*
G03X366206Y221277I-165J-1077D01*
G01X365158Y236069D02*
X365159D01*
G01D02*
X386444Y257354D01*
G01X363545Y231358D02*
X364394Y232206D01*
G01D02*
G03X364709Y233150I-763J779D01*
G01D02*
G02X365023Y234094I1077J166D01*
G01D02*
X374338Y243409D01*
G01D02*
G02X375282Y243723I778J-763D01*
G01D02*
G03X376226Y244038I165J1078D01*
G01D02*
X377074Y244887D01*
G01D02*
G03X377389Y245831I-762J779D01*
G01D02*
G02X377704Y246775I1077J165D01*
G01D02*
X378552Y247623D01*
G01D02*
G02X379496Y247938I779J-763D01*
G01X363140Y242452D02*
X363989Y243301D01*
G01D02*
G03X364303Y244245I-763J778D01*
G01D02*
G02X364618Y245189I1078J165D01*
G01D02*
X365466Y246037D01*
G01D02*
G02X366410Y246352I779J-762D01*
G01D02*
G03X367354Y246667I165J1077D01*
G01D02*
X368203Y247515D01*
G01D02*
G03X368518Y248459I-763J779D01*
G01D02*
G02X368832Y249403I1077J166D01*
G01D02*
X376420Y256991D01*
G01D02*
G02X377364Y257305I778J-763D01*
G01D02*
G03X378308Y257620I165J1078D01*
G01D02*
X379156Y258469D01*
G01X383742Y237555D02*
X382894Y236707D01*
G01D02*
G02X381950Y236392I-779J762D01*
G01D02*
G03X381006Y236077I-165J-1077D01*
G01D02*
X380157Y235229D01*
G01D02*
G03X379843Y234285I763J-778D01*
G01D02*
G02X379528Y233341I-1078J-165D01*
G01X396791Y250500D02*
G03X394464Y249536I0J-3291D01*
G01D02*
X388586Y243658D01*
G01D02*
G03X388271Y242714I763J-779D01*
G01D02*
G02X387957Y241770I-1077J-166D01*
G01D02*
X387108Y240921D01*
G01D02*
G02X386164Y240606I-779J763D01*
G01D02*
G03X385220Y240292I-166J-1077D01*
G01D02*
X384372Y239443D01*
G01D02*
G03X384057Y238499I762J-779D01*
G01D02*
G02X383742Y237555I-1077J-165D01*
G01X396790Y251800D02*
G03X393545Y250456I1J-4591D01*
G01D02*
X393045Y249956D01*
G01D02*
X393044D01*
G01D02*
X387670Y244582D01*
G01D02*
G03X387646Y244559I1642J-1737D01*
G01X379496Y247938D02*
G03X380440Y248252I166J1077D01*
G01D02*
X381289Y249101D01*
G01D02*
G03X381603Y250045I-763J778D01*
G01D02*
G02X381918Y250989I1078J165D01*
G01D02*
X382766Y251837D01*
G01D02*
G02X383710Y252152I779J-762D01*
G01D02*
G03X384654Y252467I165J1077D01*
G01D02*
X385503Y253315D01*
G01D02*
G03X385818Y254259I-763J779D01*
G01X386444Y257354D02*
G02X388488Y258200I2042J-2042D01*
G01D02*
X390911D01*
G01D02*
G03X395947Y260286I0J7123D01*
G01X385818Y254259D02*
G02X386129Y255200I1077J166D01*
G01D02*
G02X386132Y255203I772J-769D01*
G01D02*
X387364Y256435D01*
G01D02*
G02X388487Y256900I1123J-1123D01*
G01D02*
X390911D01*
G01D02*
G03X396867Y259367I0J8423D01*
G01X379156Y258469D02*
G03X379471Y259413I-762J779D01*
G01D02*
G02X379786Y260357I1077J165D01*
G01D02*
X380634Y261205D01*
G01D02*
G02X381578Y261520I779J-763D01*
G01D02*
G03X382522Y261834I166J1077D01*
G01D02*
X383371Y262683D01*
G01D02*
G03X383685Y263627I-763J778D01*
G01D02*
G02X384000Y264571I1078J165D01*
G01D02*
X384848Y265419D01*
G01D02*
G02X385792Y265734I779J-762D01*
G01D02*
G03X386736Y266049I165J1077D01*
G01D02*
X387585Y266897D01*
G01D02*
G03X387900Y267841I-763J779D01*
G01D02*
G02X388214Y268785I1077J166D01*
G01D02*
X392107Y272678D01*
G01D02*
G02X393050Y272992I778J-763D01*
G01D02*
G03X393994Y273307I165J1077D01*
G01D02*
X394843Y274155D01*
G01D02*
G03X395158Y275099I-763J779D01*
G01D02*
G02X395464Y276035I1077J166D01*
G01D02*
G02X395472Y276043I775J-767D01*
G01D02*
X396321Y276892D01*
G01X395500Y297000D02*
G02X399363Y298600I3864J-3865D01*
G01X414760Y258205D02*
X409027Y252472D01*
G01D02*
X409028D01*
G01D02*
X408959Y252403D01*
G01D02*
G02X404361Y250500I-4596J4598D01*
G01D02*
X396791D01*
G01X426186Y271470D02*
X408039Y253323D01*
G01D02*
G02X404362Y251800I-3677J3677D01*
G01D02*
X396790D01*
G01X395947Y260286D02*
X401581Y265920D01*
G01D02*
G02X404913Y267300I3333J-3334D01*
G01D02*
X410000D01*
G01D02*
G03X413348Y268688I-1J4735D01*
G01X396867Y259367D02*
X402500Y265000D01*
G01D02*
G02X404914Y266000I2414J-2414D01*
G01D02*
X410000D01*
G01D02*
G03X414268Y267768I0J6036D01*
G01X396321Y276892D02*
G02X397265Y277207I779J-763D01*
G01D02*
G03X398209Y277521I166J1077D01*
G01D02*
X399057Y278370D01*
G01D02*
G03X399372Y279314I-762J779D01*
G01D02*
G02X399687Y280258I1077J165D01*
G01D02*
X402664Y283235D01*
G01D02*
G02X414892Y288300I12228J-12228D01*
G01X398771Y281182D02*
X401744Y284154D01*
G01D02*
G02X414893Y289600I13148J-13147D01*
G01X399363Y298600D02*
X442100D01*
G01X396419Y296080D02*
G02X399364Y297300I2945J-2945D01*
G01D02*
X442100D01*
G01X427105Y270550D02*
X422341Y265786D01*
G01D02*
G03X422026Y264842I762J-779D01*
G01D02*
G02X421711Y263898I-1077J-165D01*
G01D02*
X420863Y263049D01*
G01D02*
G02X419919Y262734I-779J763D01*
G01D02*
G03X418975Y262420I-166J-1077D01*
G01D02*
X418126Y261571D01*
G01D02*
G03X417812Y260627I763J-778D01*
G01D02*
G02X417497Y259683I-1078J-165D01*
G01D02*
X416648Y258835D01*
G01D02*
G02X415704Y258520I-779J762D01*
G01D02*
G03X414760Y258205I-165J-1077D01*
G01X413348Y268688D02*
X420568Y275908D01*
G01X414268Y267768D02*
X421488Y274988D01*
G01X433275Y271000D02*
X428191D01*
G01D02*
G03X427105Y270550I0J-1536D01*
G01X463965Y272300D02*
X428190D01*
G01D02*
G03X426186Y271470I1J-2836D01*
G01X420568Y275908D02*
G02X429000Y279400I8431J-8432D01*
G01X421488Y274988D02*
G02X428999Y278100I7513J-7512D01*
G01X414892Y288300D02*
X448205D01*
G01X414893Y289600D02*
X448206D01*
G01X463964Y271000D02*
X443995D01*
G01D02*
G03X443105Y270555I-11J-1090D01*
G01D02*
G02X442215Y270110I-879J645D01*
G01D02*
X441015D01*
G01D02*
G02X440125Y270555I-11J1090D01*
G01D02*
G03X439235Y271000I-879J-645D01*
G01D02*
X438035D01*
G01D02*
G03X437145Y270555I-11J-1090D01*
G01D02*
G02X436255Y270110I-879J645D01*
G01D02*
X435055D01*
G01D02*
G02X434165Y270555I-11J1090D01*
G01D02*
G03X433275Y271000I-879J-645D01*
G01X429000Y279400D02*
X456499D01*
G01X428999Y278100D02*
X456500D01*
G01X442100Y298600D02*
G03X453709Y303408I1J16417D01*
G01X442100Y297300D02*
Y297299D01*
G01D02*
G03X454629Y302488I1J17718D01*
G01X456499Y279400D02*
G03X458985Y280431I-1J3515D01*
G01D02*
X463527Y284971D01*
G01X456500Y278100D02*
G03X459905Y279511I-1J4816D01*
G01D02*
X464447Y284051D01*
G01X454629Y302488D02*
X455720Y303580D01*
G01X448205Y288300D02*
G03X452805Y290205I0J6506D01*
G01D02*
X472850Y310250D01*
G01X448206Y289600D02*
G03X451885Y291125I-2J5205D01*
G01D02*
X471930Y311170D01*
G01X453709Y303408D02*
X454800Y304500D01*
G01D02*
X465376Y315075D01*
G01X455720Y303580D02*
X465904Y313764D01*
G01X497954Y279300D02*
X475166D01*
G01D02*
G03X472824Y278330I0J-3312D01*
G01D02*
X466574Y272080D01*
G01D02*
G02X463964Y271000I-2608J2610D01*
G01X497953Y280600D02*
X475166D01*
G01D02*
G03X471904Y279249I-1J-4612D01*
G01D02*
X465655Y273000D01*
G01D02*
G02X463965Y272300I-1690J1690D01*
G01X463527Y284971D02*
G02X470115Y287700I6588J-6588D01*
G01X464447Y284051D02*
G02X470116Y286400I5670J-5667D01*
G01D02*
X491276D01*
G01X470115Y287700D02*
X491275D01*
G01X465376Y315075D02*
X466593Y316292D01*
G01D02*
G02X471200Y318200I4607J-4608D01*
G01D02*
X482989D01*
G01X465904Y313764D02*
X465905D01*
G01D02*
X467513Y315372D01*
G01D02*
G02X471201Y316900I3688J-3687D01*
G01D02*
X486023D01*
G01X472850Y310250D02*
G02X478282Y312500I5432J-5432D01*
G01X471930Y311170D02*
G02X478283Y313800I6351J-6353D01*
G01X491276Y286400D02*
G03X494654Y287799I-1J4779D01*
G01X491275Y287700D02*
G03X493735Y288719I0J3479D01*
G01D02*
X501135Y296119D01*
G01X482989Y318200D02*
G03X483955Y318600I0J1366D01*
G01X486023Y316900D02*
G03X486588Y317134I0J799D01*
G01D02*
X487377Y317921D01*
G01D02*
G03X487612Y318487I-564J566D01*
G01D02*
Y318606D01*
G01X478282Y312500D02*
X489960D01*
G01D02*
G03X491725Y313230I1J2496D01*
G01D02*
X493983Y315488D01*
G01D02*
G02X495103Y315952I1120J-1120D01*
G01X478283Y313800D02*
X489961D01*
G01D02*
G03X490805Y314150I-1J1195D01*
G01D02*
X490855Y314200D01*
G01D02*
G03X491257Y315171I-971J971D01*
G01D02*
Y315952D01*
G01X508665Y288270D02*
X500924Y280530D01*
G01D02*
G02X497954Y279300I-2971J2972D01*
G01X507745Y289190D02*
X500005Y281450D01*
G01D02*
G02X497953Y280600I-2052J2052D01*
G01X510955Y293799D02*
G02X508665Y288270I-7822J1D01*
G01X509655Y318000D02*
Y293800D01*
G01D02*
G02X507745Y289190I-6521J1D01*
G01X501135Y296119D02*
G03X501855Y297857I-1738J1738D01*
G01D02*
Y312100D01*
G01X494654Y287799D02*
X502055Y295200D01*
G01D02*
G03X503155Y297856I-2658J2657D01*
G01D02*
Y299629D01*
G01D02*
G02X503600Y300519I1090J11D01*
G01D02*
G03X504045Y301409I-645J879D01*
G01D02*
Y302609D01*
G01D02*
G03X503600Y303499I-1090J11D01*
G01X509057Y319442D02*
G02X509655Y318000I-1442J-1443D01*
G01X501855Y312100D02*
G03X501253Y313555I-2057J1D01*
G01D02*
X500607Y314200D01*
G01X503600Y303499D02*
G02X503155Y304389I645J879D01*
G01D02*
Y312100D01*
G01D02*
G02X503722Y313469I1936J0D01*
G01D02*
X504453Y314200D01*
G01X508500Y320000D02*
X509057Y319442D01*
G01X510955Y318000D02*
Y293799D01*
G01X511630Y319631D02*
G03X510955Y318000I1631J-1630D01*
G01X512000Y320000D02*
X511630Y319631D01*
G54D11*
G01X1090028Y126500D02*
X1090055Y126528D01*
G01D02*
G03X1091411Y129800I-3272J3273D01*
G01D02*
Y139717D01*
G01X1093894Y126500D02*
X1093867Y126528D01*
G01D02*
G02X1092511Y129800I3272J3273D01*
G01D02*
Y139718D01*
G01X1091411Y139717D02*
G03X1090622Y141622I-2693J1D01*
G01D02*
X1090429Y141815D01*
G01D02*
G02X1089400Y144300I2486J2485D01*
G01D02*
Y209101D01*
G01X1092511Y139718D02*
G03X1091400Y142400I-3793J0D01*
G01D02*
X1091207Y142593D01*
G01D02*
G02X1090500Y144300I1707J1707D01*
G01D02*
Y159669D01*
G01D02*
G02X1090795Y160259I789J-26D01*
G01D02*
G03X1091090Y160849I-495J616D01*
G01D02*
Y162349D01*
G01D02*
G03X1090795Y162939I-789J-26D01*
G01D02*
G02X1090500Y163529I495J616D01*
G01D02*
Y170598D01*
G01D02*
G02X1090795Y171188I790J-26D01*
G01D02*
G03X1091090Y171778I-495J616D01*
G01D02*
Y173278D01*
G01D02*
G03X1090795Y173868I-790J-26D01*
G01D02*
G02X1090500Y174458I495J616D01*
G01D02*
Y175958D01*
G01D02*
G02X1090795Y176548I790J-26D01*
G01D02*
G03X1091090Y177138I-495J616D01*
G01D02*
Y178638D01*
G01D02*
G03X1090795Y179228I-790J-26D01*
G01D02*
G02X1090500Y179818I495J616D01*
G01D02*
Y189615D01*
G01D02*
G02X1090795Y190205I790J-26D01*
G01D02*
G03X1091090Y190795I-494J616D01*
G01D02*
Y192295D01*
G01D02*
G03X1090795Y192885I-790J-26D01*
G01D02*
G02X1090500Y193475I494J616D01*
G01D02*
Y194975D01*
G01D02*
G02X1090795Y195565I790J-26D01*
G01D02*
G03X1091090Y196155I-494J616D01*
G01D02*
Y197655D01*
G01D02*
G03X1090795Y198245I-790J-26D01*
G01D02*
G02X1090500Y198835I494J616D01*
G01D02*
Y200335D01*
G01D02*
G02X1090795Y200925I790J-26D01*
G01D02*
G03X1091090Y201515I-494J616D01*
G01D02*
Y203015D01*
G01D02*
G03X1090795Y203605I-790J-26D01*
G01D02*
G02X1090500Y204195I494J616D01*
G01D02*
Y209100D01*
G01X1089400Y209101D02*
G02X1091773Y214828I8101J-1D01*
G01D02*
X1104091Y227147D01*
G01X1090500Y209100D02*
G02X1092551Y214050I7001J-1D01*
G01D02*
X1104869Y226369D01*
G01X1104091Y227147D02*
G03X1104900Y229100I-1953J1953D01*
G01D02*
Y296965D01*
G01X1104869Y226369D02*
G03X1106000Y229100I-2732J2731D01*
G01D02*
Y296964D01*
G01X1104900Y296965D02*
G02X1105954Y299510I3600J0D01*
G01D02*
X1152668Y346224D01*
G01X1106000Y296964D02*
G02X1106732Y298732I2500J0D01*
G01D02*
X1153446Y345446D01*
G01X1152668Y346224D02*
G03X1153400Y347992I-1768J1768D01*
G01D02*
Y363000D01*
G01X1153446Y345446D02*
G03X1154500Y347991I-2546J2545D01*
G01D02*
Y363000D01*
G01X1153400D02*
G03X1152662Y364782I-2520J0D01*
G01D02*
X1151822Y365622D01*
G01D02*
G02X1151000Y367606I1985J1985D01*
G01D02*
Y426567D01*
G01X1154500Y363000D02*
G03X1153440Y365560I-3621J0D01*
G01D02*
X1152600Y366400D01*
G01D02*
G02X1152100Y367607I1207J1207D01*
G01D02*
Y426567D01*
G01X1151000D02*
G02X1152055Y429113I3600J0D01*
G01D02*
X1158267Y435322D01*
G01X1152100Y426567D02*
G02X1152833Y428335I2500J-1D01*
G01D02*
X1159045Y434544D01*
G01X1158267Y435322D02*
G03X1159000Y437090I-1767J1768D01*
G01D02*
Y446866D01*
G01D02*
G03X1157591Y448275I-1409J0D01*
G01D02*
X1157090D01*
G01D02*
G03X1156737Y448129I0J-500D01*
G01D02*
X1155500Y446892D01*
G01X1159045Y434544D02*
G03X1160100Y437090I-2545J2546D01*
G01D02*
Y446866D01*
G01D02*
G03X1157591Y449375I-2509J0D01*
G01D02*
X1157090D01*
G01D02*
G02X1156737Y449521I0J500D01*
G01D02*
X1155500Y450758D01*
G54D12*
G01X1Y-17717D02*
G03X7875Y-25591I7874J0D01*
G01X1Y299252D02*
Y-10394D01*
G01Y-17717D02*
G03X7875Y-25591I7874J0D01*
G01X1Y299252D02*
Y-10394D01*
G01Y-17717D02*
Y-10394D01*
G01D02*
Y-17723D01*
G01X0Y11811D02*
Y0D01*
G01X92520Y299252D02*
X1D01*
G01X92520D02*
X1D01*
G01X1008465Y988189D02*
G03X988780Y968504I0J-19685D01*
G01Y775591D01*
G02X984843Y771654I-3937J0D01*
G01X925787D01*
G02X921850Y775591I0J3937D01*
G01Y968504D01*
G03X902165Y988189I-19685J0D01*
G01X800984D01*
G02X797047Y992126I0J3937D01*
G01Y1021653D01*
X795078Y1023622D01*
X754921D01*
X752952Y1021653D01*
X752953Y1018110D01*
Y994291D01*
G02X745472I-3740J0D01*
G01Y1021653D01*
X743504Y1023622D01*
X719094D01*
X717126Y1021653D01*
Y992126D01*
G02X713189Y988189I-3937J0D01*
G01X600984D01*
G02X597047Y992126I0J3937D01*
G01Y1021653D01*
X595078Y1023622D01*
X554921D01*
X552952Y1021653D01*
X552953Y1018110D01*
Y994291D01*
G02X545472I-3741J0D01*
G01Y1021653D01*
X543504Y1023622D01*
X267126D01*
X265157Y1021653D01*
Y992126D01*
G02X261220Y988189I-3937J0D01*
G01X191535D01*
G02X187598Y992126I0J3937D01*
G01Y1021653D01*
X185630Y1023622D01*
X145472D01*
X143504Y1021653D01*
Y994291D01*
G02X136024I-3740J0D01*
G01Y1018110D01*
X136023Y1021653D01*
X134055Y1023622D01*
X109645D01*
X107677Y1021653D01*
Y992126D01*
G02X103740Y988189I-3937J0D01*
G01X19685D01*
G03X0Y968504I0J-19685D01*
G01Y318937D01*
G03X11811Y307126I11811J0D01*
G01X100394D01*
G02X108268Y299252I0J-7874D01*
G01Y236260D01*
G03X116142Y228386I7874J0D01*
G01X239961D01*
G02X243898Y224449I0J-3937D01*
G01Y70866D01*
G03X247835Y66929I3937J0D01*
G01X289173D01*
G02X293110Y62992I0J-3937D01*
G01Y3937D01*
G03X297047Y0I3937J0D01*
G01X1108209D01*
G03X1112146Y3937I0J3937D01*
G01Y210630D01*
G02X1116083Y214567I3937J0D01*
G01X1194823D01*
G02X1198760Y210630I0J-3937D01*
G01Y179134D01*
G03X1202697Y175197I3937J0D01*
G02X1206634Y171260I0J-3937D01*
G01Y3937D01*
G03X1210571Y0I3937J0D01*
G01X1396063D01*
G03X1400000Y3937I0J3937D01*
G01Y968504D01*
G03X1380315Y988189I-19685J0D01*
G01X1008465D01*
G01X0Y318937D02*
G03X11811Y307126I11811J0D01*
G01X0Y968503D02*
Y318937D01*
G01X19685Y988189D02*
G03X0Y968503I0J-19685D01*
G01X43950Y996063D02*
X1D01*
G01X43950D02*
X1D01*
G01Y1008622D02*
Y996063D01*
G01Y1008622D02*
Y996063D01*
G01X15001Y1023622D02*
G03X1Y1008622I0J-15000D01*
G01X15001Y1023622D02*
G03X1Y1008622I0J-15000D01*
G01X7875Y-25591D02*
X45337D01*
G01X7875D02*
X45337D01*
G01X11811Y307126D02*
X100394D01*
G01X10710Y1008622D02*
G03X19292I4291J0D01*
G01D02*
G03X10710I-4291J0D01*
G01X99804Y1023622D02*
X15001D01*
G01X99804D02*
X15001D01*
G01X103740Y988189D02*
X19685D01*
G01X53211Y-25591D02*
G03X45337I-3937J0D01*
G01X53211D02*
G03X45337I-3937J0D01*
G01X53211D02*
G03X45337I-3937J0D01*
G01X53211D02*
G03X45337I-3937J0D01*
G01X43950Y988189D02*
G03Y996063I0J3937D01*
G01Y988189D02*
G03Y996063I0J3937D01*
G01X53211Y-25591D02*
X1392127D01*
G01X53211D02*
X1392127D01*
G01X69147Y996063D02*
G03Y988189I0J-3937D01*
G01Y996063D02*
G03Y988189I0J-3937D01*
G01X99804Y996063D02*
X69147D01*
G01X99804D02*
X69147D01*
G01X94412Y72220D02*
G03X85830Y72219I-4291J-1D01*
G01D02*
G03X94412Y72220I4291J0D01*
G01X100394Y291377D02*
G03X92520Y299252I-7874J1D01*
G01X100394Y291377D02*
G03X92520Y299252I-7874J1D01*
G01X99804Y1023622D02*
Y996063D01*
G01Y1023622D02*
Y996063D01*
G01X100394Y236259D02*
G03X116142Y220511I15748J0D01*
G01D02*
X232088D01*
G01X100394Y236259D02*
G03X116142Y220511I15748J0D01*
G01D02*
X232088D01*
G01X116142Y228385D02*
X239961D01*
G01X108268Y236259D02*
G03X116142Y228385I7874J0D01*
G01X108268Y299252D02*
Y236259D01*
G01X100395Y240899D02*
X100394Y236259D01*
G01X100395Y240899D02*
X100394Y236259D01*
G01X108269Y240899D02*
G03X100395I-3937J0D01*
G01X108269D02*
G03X100395I-3937J0D01*
G01Y266096D02*
G03X108269I3937J-1D01*
G01X100395D02*
G03X108269I3937J-1D01*
G01X100395D02*
X100394Y291377D01*
G01X100395Y266096D02*
X100394Y291377D01*
G01X108268Y299252D02*
G03X100394Y307126I-7874J0D01*
G01X103740Y988189D02*
G03X107677Y992126I0J3937D01*
G01Y1018109D02*
Y992126D01*
G01X136024Y1018109D02*
X136023Y1021653D01*
X134055Y1023622D01*
X109645D01*
X107677Y1021653D01*
Y1018109D01*
G01X136024Y994290D02*
G03X143505I3740J0D01*
G01X136024D02*
Y1018109D01*
G01X143504D02*
Y994290D01*
G01X187598Y1018109D02*
Y1021653D01*
X185630Y1023622D01*
X145472D01*
X143504Y1021653D01*
Y1018109D01*
G01X151575Y220511D02*
X226378D01*
G01X151575D02*
X226378D01*
G01X187598Y992126D02*
Y1018109D01*
G01Y992126D02*
G03X191535Y988189I3937J0D01*
G01X261220D02*
X191535D01*
G01X212681Y996063D02*
X195473D01*
G01D02*
Y1023622D01*
G01X212681Y996063D02*
X195473D01*
G01D02*
Y1023622D01*
G01D02*
X257284D01*
G01X195473D02*
X257284D01*
G01X212681Y988189D02*
G03Y996063I0J3937D01*
G01Y988189D02*
G03Y996063I0J3937D01*
G01X222751Y1008622D02*
G03X231333I4291J0D01*
G01D02*
G03X222751I-4291J0D01*
G01X243898Y70866D02*
G03X247835Y66928I3937J-1D01*
G01X243898Y224448D02*
Y70866D01*
G01X236025Y164487D02*
Y70866D01*
G01D02*
G03X247836Y59055I11811J0D01*
G01X236025Y164487D02*
Y70866D01*
G01D02*
G03X247836Y59055I11811J0D01*
G01X243899Y164487D02*
G03X236025I-3937J0D01*
G01X243899D02*
G03X236025I-3937J0D01*
G01Y189684D02*
G03X243899I3937J0D01*
G01X236025D02*
G03X243899I3937J0D01*
G01X236025D02*
Y216574D01*
G01Y189684D02*
Y216574D01*
G01D02*
G03X232088Y220511I-3937J0D01*
G01X236025Y216574D02*
G03X232088Y220511I-3937J0D01*
G01X243898Y224448D02*
G03X239961Y228385I-3937J0D01*
G01X237877Y996063D02*
G03Y988189I0J-3937D01*
G01Y996063D02*
G03Y988189I0J-3937D01*
G01X257284Y996063D02*
X237877D01*
G01X257284D02*
X237877D01*
G01X247835Y66929D02*
X289174D01*
G01X247836Y59055D02*
X285237D01*
G01X247836D02*
X285237D01*
G01X261220Y988189D02*
G03X265157Y992126I0J3937D01*
G01X257284Y1023622D02*
Y996063D01*
G01Y1023622D02*
Y996063D01*
G01X265157Y1018109D02*
Y992126D01*
G01X545472Y1018109D02*
Y1021653D01*
X543504Y1023622D01*
X267126D01*
X265157Y1021653D01*
Y1018109D01*
G01X293111Y3937D02*
G03X297047Y0I3937J0D01*
G01X293110Y62992D02*
Y3937D01*
G01X285237D02*
G03X297048Y-7874I11811J0D01*
G01X285237Y59055D02*
Y3937D01*
G01D02*
G03X297048Y-7874I11811J0D01*
G01X285237Y59055D02*
Y3937D01*
G01X293111Y62992D02*
G03X289174Y66929I-3937J0D01*
G01X297047Y0D02*
X1108209D01*
G01X297037Y-7874D02*
X301187D01*
G01D02*
G03Y0I0J3937D01*
G01X297037Y-7874D02*
X301187D01*
G01D02*
G03Y0I0J3937D01*
G01X318510Y-7874D02*
X515333D01*
G01X318510Y0D02*
G03Y-7874I0J-3937D01*
G01D02*
X515333D01*
G01X318510Y0D02*
G03Y-7874I0J-3937D01*
G01X515302D02*
G03Y0I0J3937D01*
G01Y-7874D02*
G03Y0I0J3937D01*
G01X540499Y-7874D02*
X727049D01*
G01X540499Y0D02*
G03Y-7874I0J-3937D01*
G01D02*
X727049D01*
G01X540499Y0D02*
G03Y-7874I0J-3937D01*
G01X545472Y994290D02*
G03X552953I3740J1D01*
G01X545472D02*
Y1018109D01*
G01X552953D02*
Y994290D01*
G01X597047Y1018109D02*
Y1021653D01*
X595078Y1023622D01*
X554921D01*
X552952Y1021653D01*
X552953Y1018109D01*
G01X597047Y992126D02*
Y1018109D01*
G01X597048Y992126D02*
G03X600984Y988189I3937J0D01*
G01X713189D02*
X600984D01*
G01X641198Y996063D02*
X604922D01*
G01D02*
Y1023622D01*
G01X641198Y996063D02*
X604922D01*
G01D02*
Y1023622D01*
G01D02*
X709253D01*
G01X604922D02*
X709253D01*
G01X641198Y988189D02*
G03Y996063I0J3937D01*
G01Y988189D02*
G03Y996063I0J3937D01*
G01X649684Y1008622D02*
G03X658266I4291J0D01*
G01D02*
G03X649684I-4291J0D01*
G01X666395Y996063D02*
G03Y988189I0J-3937D01*
G01Y996063D02*
G03Y988189I0J-3937D01*
G01X709253Y996063D02*
X666395D01*
G01X709253D02*
X666395D01*
G01X713189Y988189D02*
G03X717126Y992126I0J3937D01*
G01Y1018109D02*
Y992126D01*
G01X709253Y1023622D02*
Y996063D01*
G01Y1023622D02*
Y996063D01*
G01X745472Y1018109D02*
Y1021653D01*
X743504Y1023622D01*
X719094D01*
X717126Y1021653D01*
Y1018109D01*
G01X727049Y-7874D02*
G03Y0I0J3937D01*
G01Y-7874D02*
G03Y0I0J3937D01*
G01X752246Y-7874D02*
X984201D01*
G01X752246Y0D02*
G03Y-7874I0J-3937D01*
G01D02*
X984201D01*
G01X752246Y0D02*
G03Y-7874I0J-3937D01*
G01X745472Y994290D02*
G03X752953I3741J1D01*
G01X745472D02*
Y1018109D01*
G01X752953D02*
Y994290D01*
G01X797047Y1018109D02*
Y1021653D01*
X795078Y1023622D01*
X754921D01*
X752952Y1021653D01*
X752953Y1018109D01*
G01X797047Y992126D02*
Y1018109D01*
G01X797048Y992126D02*
G03X800984Y988189I3937J0D01*
G01X902165D02*
X800984D01*
G01X859109Y996063D02*
X804922D01*
G01D02*
Y1023622D01*
G01X859109Y996063D02*
X804922D01*
G01D02*
Y1023622D01*
G01D02*
X1325399D01*
G01X804922D02*
X1325399D01*
G01X859109Y988189D02*
G03Y996063I0J3937D01*
G01Y988189D02*
G03Y996063I0J3937D01*
G01X884306D02*
G03Y988189I0J-3937D01*
G01Y996063D02*
G03Y988189I0J-3937D01*
G01X902166Y996063D02*
X884306D01*
G01X902166D02*
X884306D01*
G01X921850Y968503D02*
G03X902165Y988189I-19685J1D01*
G01X929725Y968504D02*
G03X902166Y996063I-27559J0D01*
G01D02*
X902195D01*
G01X929725Y968504D02*
G03X902166Y996063I-27559J0D01*
G01D02*
X902195D01*
G01X921850Y775590D02*
Y968503D01*
G01Y775590D02*
G03X925787Y771653I3937J0D01*
G01X984843D02*
X925787D01*
G01X929725Y779527D02*
Y886881D01*
G01Y779527D02*
X980906D01*
G01X929725D02*
Y886881D01*
G01Y779527D02*
X980906D01*
G01X929725Y886881D02*
G03X921851I-3937J1D01*
G01X929725D02*
G03X921851I-3937J1D01*
G01Y912079D02*
G03X929725I3937J-1D01*
G01X921851D02*
G03X929725I3937J-1D01*
G01Y912078D02*
Y968504D01*
G01Y912078D02*
Y968504D01*
G01X959606Y850829D02*
G03X951024I-4291J0D01*
G01D02*
G03X959606I4291J0D01*
G01X984201Y-7874D02*
G03Y0I0J3937D01*
G01Y-7874D02*
G03Y0I0J3937D01*
G01X984843Y771653D02*
G03X988780Y775590I0J3937D01*
G01X980907Y886881D02*
X980906Y779527D01*
G01X980907Y886881D02*
X980906Y779527D01*
G01X988781Y886881D02*
G03X980907I-3937J1D01*
G01X988781D02*
G03X980907I-3937J1D01*
G01Y912079D02*
G03X988781I3937J-1D01*
G01X980907D02*
G03X988781I3937J-1D01*
G01X980907D02*
X980906Y968504D01*
G01X980907Y912079D02*
X980906Y968504D01*
G01X1008465Y996063D02*
G03X980906Y968504I0J-27559D01*
G01X1008465Y996063D02*
G03X980906Y968504I0J-27559D01*
G01X1011417Y237795D02*
X1005118D01*
G02Y250394I0J6300D01*
G01X1011417D01*
G02Y237795I0J-6299D01*
G01Y405118D02*
X1005118D01*
G02Y417717I0J6300D01*
G01X1011417D01*
G02Y405118I0J-6299D01*
G01X988780Y968503D02*
Y775590D01*
G01X1008465Y988189D02*
G03X988780Y968503I0J-19685D01*
G01X1009398Y-7874D02*
X1108229D01*
G01X1009398Y0D02*
G03Y-7874I-1J-3937D01*
G01D02*
X1108229D01*
G01X1009398Y0D02*
G03Y-7874I-1J-3937D01*
G01X1380315Y988189D02*
X1008465D01*
G01X1070592Y996063D02*
X1008466D01*
G01X1070592D02*
X1008466D01*
G01X1070592Y988189D02*
G03Y996063I0J3937D01*
G01Y988189D02*
G03Y996063I0J3937D01*
G01X1095789D02*
G03Y988189I0J-3937D01*
G01Y996063D02*
G03Y988189I0J-3937D01*
G01X1325399Y996063D02*
X1095789D01*
G01X1325399D02*
X1095789D01*
G01X1112146Y3937D02*
Y210629D01*
G01X1108209Y0D02*
G03X1112146Y3937I0J3937D01*
G01X1108208Y-7874D02*
G03X1120020Y3938I1J11811D01*
G01X1108208Y-7874D02*
G03X1120020Y3938I1J11811D01*
G01Y99950D02*
G03X1112146I-3937J0D01*
G01X1120020D02*
G03X1112146I-3937J0D01*
G01Y125147D02*
G03X1120020I3937J0D01*
G01X1112146D02*
G03X1120020I3937J0D01*
G01X1116083Y214566D02*
X1194824D01*
G01X1116083D02*
G03X1112146Y210629I0J-3937D01*
G01X1120020Y99950D02*
Y3938D01*
G01Y99950D02*
Y3938D01*
G01Y125147D02*
Y206693D01*
G01Y125147D02*
Y206693D01*
G01X1120021D02*
X1190887D01*
G01X1120021D02*
X1190887D01*
G01X1161386Y128841D02*
G03X1152804I-4291J0D01*
G01D02*
G03X1161386I4291J0D01*
G01X1198760Y3937D02*
G03X1210571Y-7874I11811J0D01*
G01X1198760Y3937D02*
G03X1210571Y-7874I11811J0D01*
G01X1198761Y97100D02*
X1198760Y3937D01*
G01X1198761Y97100D02*
X1198760Y3937D01*
G01X1206635Y97100D02*
G03X1198761I-3937J0D01*
G01X1206635D02*
G03X1198761I-3937J0D01*
G01Y122297D02*
G03X1206635I3937J0D01*
G01X1198761D02*
G03X1206635I3937J0D01*
G01X1198761D02*
Y168002D01*
G01Y122297D02*
Y168002D01*
G01X1190887Y179134D02*
G03X1198761Y167998I11811J0D01*
G01X1190887Y179134D02*
G03X1198761Y167998I11811J0D01*
G01X1198760Y179133D02*
G03X1202697Y175196I3937J0D01*
G01X1198760Y210629D02*
Y179133D01*
G01X1190887Y206693D02*
Y179134D01*
G01Y206693D02*
Y179134D01*
G01X1198760Y210629D02*
G03X1194824Y214566I-3937J0D01*
G01X1210571Y0D02*
X1396063D01*
G01X1206634Y3937D02*
G03X1210571Y0I3937J0D01*
G01X1206634Y171259D02*
Y3937D01*
G01X1210552Y-7874D02*
X1210572D01*
G01D02*
G03Y0I0J3937D01*
G01X1210552Y-7874D02*
X1210572D01*
G01D02*
G03Y0I0J3937D01*
G01X1206634Y171259D02*
G03X1202697Y175196I-3937J0D01*
G01X1226320Y-7874D02*
X1380317D01*
G01X1226320Y0D02*
G03Y-7874I0J-3937D01*
G01D02*
X1380317D01*
G01X1226320Y0D02*
G03Y-7874I0J-3937D01*
G01X1230315Y149213D02*
X1224016D01*
G02Y161811I0J6299D01*
G01X1230315D01*
G02Y149213I0J-6299D01*
G01Y405118D02*
X1224016D01*
G02Y417717I0J6300D01*
G01X1230315D01*
G02Y405118I0J-6299D01*
G01X1354801Y996063D02*
X1325399D01*
G01X1354801D02*
X1325399D01*
G01Y1023622D02*
X1385001D01*
G01X1325399D02*
X1385001D01*
G01X1354801Y988189D02*
G03Y996063I0J3937D01*
G01Y988189D02*
G03Y996063I0J3937D01*
G01X1380316Y-7874D02*
G03Y0I0J3937D01*
G01Y-7874D02*
G03Y0I0J3937D01*
G01X1400000Y968503D02*
G03X1380315Y988189I-19685J1D01*
G01X1379998Y996063D02*
G03Y988189I0J-3937D01*
G01Y996063D02*
G03Y988189I0J-3937D01*
G01X1400001Y996063D02*
X1379998D01*
G01X1400001D02*
X1379998D01*
G01X1392127Y-25591D02*
G03X1400001Y-17717I0J7874D01*
G01X1392167Y-15015D02*
G03X1383585I-4291J0D01*
G01D02*
G03X1392167I4291J0D01*
G01X1392127Y-25591D02*
G03X1400001Y-17717I0J7874D01*
G01X1396063Y0D02*
G03X1400000Y3937I0J3937D01*
G01X1396064Y-7874D02*
X1400001D01*
G01X1396064Y0D02*
G03Y-7874I0J-3937D01*
G01D02*
X1400001D01*
G01X1396064Y0D02*
G03Y-7874I0J-3937D01*
G01X1380710Y1008622D02*
G03X1389292I4291J0D01*
G01D02*
G03X1380710I-4291J0D01*
G01X1400001D02*
G03X1385001Y1023622I-15000J0D01*
G01X1400001Y1008622D02*
G03X1385001Y1023622I-15000J0D01*
G01X1400001Y-17717D02*
Y-7874D01*
G01Y-17717D02*
Y-7874D01*
G01X1400000Y3937D02*
Y968503D01*
G01X1400001Y996063D02*
Y1008622D01*
G01Y996063D02*
Y1008622D01*
M02*
